(kicad_pcb
	(version 20260206)
	(generator "pcbnew")
	(generator_version "10.0")
	(general
		(thickness 1.6)
		(legacy_teardrops no)
	)
	(paper "A4")
	(title_block
		(title "01162023_DA0F0TEBIF0_F0T_Expander_BD_F_brd_V02_OCP.brd")
		(comment 1 "Grand Teton / footprints 2479-2485 of 9728")
	)
	(layers
		(0 "F.Cu" signal "TOP")
		(4 "In1.Cu" signal "GND")
		(6 "In2.Cu" signal "VCC")
		(8 "In3.Cu" signal "VCC1")
		(10 "In4.Cu" signal "GND1")
		(12 "In5.Cu" signal "IN1")
		(14 "In6.Cu" signal "GND2")
		(16 "In7.Cu" signal "IN2")
		(18 "In8.Cu" signal "GND3")
		(20 "In9.Cu" signal "IN3")
		(22 "In10.Cu" signal "GND4")
		(24 "In11.Cu" signal "IN4")
		(26 "In12.Cu" signal "GND5")
		(28 "In13.Cu" signal "IN5")
		(30 "In14.Cu" signal "GND6")
		(32 "In15.Cu" signal "IN6")
		(34 "In16.Cu" signal "GND7")
		(2 "B.Cu" signal "BOTTOM")
		(9 "F.Adhes" user "F.Adhesive")
		(11 "B.Adhes" user "B.Adhesive")
		(13 "F.Paste" user "Package Geometry/Pastemask Top")
		(15 "B.Paste" user "Package Geometry/Pastemask Bottom")
		(5 "F.SilkS" user "Ref Des/Silkscreen Top")
		(7 "B.SilkS" user "Ref Des/Silkscreen Bottom")
		(1 "F.Mask" user "Board Geometry/Soldermask Top")
		(3 "B.Mask" user "Board Geometry/Soldermask Bottom")
		(17 "Dwgs.User" user "User.Drawings")
		(19 "Cmts.User" user "User.Comments")
		(21 "Eco1.User" user "User.Eco1")
		(23 "Eco2.User" user "User.Eco2")
		(25 "Edge.Cuts" user "Board Geometry/Outline")
		(27 "Margin" user)
		(31 "F.CrtYd" user "Package Geometry/Place Bound Top")
		(29 "B.CrtYd" user "Package Geometry/Place Bound Bottom")
		(35 "F.Fab" user "Ref Des/Assembly Top")
		(33 "B.Fab" user "Ref Des/Assembly Bottom")
	)
	(footprint ""
		(layer "F.Cu")
		(at 137.7696 -214.963756 90)
		(property "Reference" "R6643"
			(at 0 0 90)
			(layer "F.SilkS")
			(hide yes)
			(effects
				(font
					(size 1.27 1.27)
				)
			)
		)
		(property "Value" ""
			(at 0 0 90)
			(layer "F.Fab")
			(effects
				(font
					(size 1.27 1.27)
				)
			)
		)
		(duplicate_pad_numbers_are_jumpers no)
		(fp_line
			(start 0.7874 -0.4064)
			(end 0.7874 0.4064)
			(stroke
				(width 0.1524)
				(type default)
			)
			(layer "F.SilkS")
		)
		(fp_line
			(start -0.7874 -0.4064)
			(end 0.7874 -0.4064)
			(stroke
				(width 0.1524)
				(type default)
			)
			(layer "F.SilkS")
		)
		(fp_line
			(start 0.7874 0.4064)
			(end -0.7874 0.4064)
			(stroke
				(width 0.1524)
				(type default)
			)
			(layer "F.SilkS")
		)
		(fp_line
			(start -0.7874 0.4064)
			(end -0.7874 -0.4064)
			(stroke
				(width 0.1524)
				(type default)
			)
			(layer "F.SilkS")
		)
		(fp_line
			(start -0.12065 -0.305054)
			(end -0.12065 -0.2794)
			(stroke
				(width 0.1)
				(type default)
			)
			(layer "F.Fab")
		)
		(fp_line
			(start -0.67945 -0.305054)
			(end -0.12065 -0.305054)
			(stroke
				(width 0.1)
				(type default)
			)
			(layer "F.Fab")
		)
		(fp_line
			(start 0.67945 -0.3048)
			(end 0.67945 0.3048)
			(stroke
				(width 0.1)
				(type default)
			)
			(layer "F.Fab")
		)
		(fp_line
			(start 0.12065 -0.3048)
			(end 0.67945 -0.3048)
			(stroke
				(width 0.1)
				(type default)
			)
			(layer "F.Fab")
		)
		(fp_line
			(start 0.12065 -0.2794)
			(end 0.12065 -0.3048)
			(stroke
				(width 0.1)
				(type default)
			)
			(layer "F.Fab")
		)
		(fp_line
			(start -0.12065 -0.2794)
			(end 0.12065 -0.2794)
			(stroke
				(width 0.1)
				(type default)
			)
			(layer "F.Fab")
		)
		(fp_line
			(start 0.120396 0.2794)
			(end -0.12065 0.2794)
			(stroke
				(width 0.1)
				(type default)
			)
			(layer "F.Fab")
		)
		(fp_line
			(start -0.12065 0.2794)
			(end -0.12065 0.3048)
			(stroke
				(width 0.1)
				(type default)
			)
			(layer "F.Fab")
		)
		(fp_line
			(start 0.67945 0.3048)
			(end 0.120396 0.3048)
			(stroke
				(width 0.1)
				(type default)
			)
			(layer "F.Fab")
		)
		(fp_line
			(start 0.120396 0.3048)
			(end 0.120396 0.2794)
			(stroke
				(width 0.1)
				(type default)
			)
			(layer "F.Fab")
		)
		(fp_line
			(start -0.12065 0.3048)
			(end -0.67945 0.3048)
			(stroke
				(width 0.1)
				(type default)
			)
			(layer "F.Fab")
		)
		(fp_line
			(start -0.67945 0.3048)
			(end -0.67945 -0.305054)
			(stroke
				(width 0.1)
				(type default)
			)
			(layer "F.Fab")
		)
		(pad "1" smd circle
			(at -0.40005 0 90)
			(size 0 0)
			(layers "F.Cu" "F.Mask" "F.Paste")
			(net "UART_PEX2_CLI_RX")
		)
		(pad "2" smd circle
			(at 0.40005 0 90)
			(size 0 0)
			(layers "F.Cu" "F.Mask" "F.Paste")
			(net "UART_PEX2_CLI_R_RX")
		)
	)
	(footprint ""
		(layer "F.Cu")
		(at 312.21934 -149.79015 180)
		(property "Reference" "C430"
			(at 0 0 180)
			(layer "F.SilkS")
			(hide yes)
			(effects
				(font
					(size 1.27 1.27)
				)
			)
		)
		(property "Value" ""
			(at 0 0 180)
			(layer "F.Fab")
			(effects
				(font
					(size 1.27 1.27)
				)
			)
		)
		(duplicate_pad_numbers_are_jumpers no)
		(fp_line
			(start 0.299974 0.150114)
			(end -0.299974 0.150114)
			(stroke
				(width 0.1)
				(type default)
			)
			(layer "F.Fab")
		)
		(fp_line
			(start 0.299974 -0.150114)
			(end 0.299974 0.150114)
			(stroke
				(width 0.1)
				(type default)
			)
			(layer "F.Fab")
		)
		(fp_line
			(start -0.299974 0.150114)
			(end -0.299974 -0.150114)
			(stroke
				(width 0.1)
				(type default)
			)
			(layer "F.Fab")
		)
		(fp_line
			(start -0.299974 -0.150114)
			(end 0.299974 -0.150114)
			(stroke
				(width 0.1)
				(type default)
			)
			(layer "F.Fab")
		)
		(pad "1" smd rect
			(at -0.2667 0 180)
			(size 0.3048 0.381)
			(layers "F.Cu" "F.Mask" "F.Paste")
			(net "P5E_PEX2_STN0_TX_DP<12>")
		)
		(pad "2" smd rect
			(at 0.2667 0 180)
			(size 0.3048 0.381)
			(layers "F.Cu" "F.Mask" "F.Paste")
			(net "P5E_PEX2_STN0_TX_C_DP<12>")
		)
	)
	(footprint ""
		(layer "F.Cu")
		(at 129.534666 -133.088126 180)
		(property "Reference" "PC329"
			(at 0 0 180)
			(layer "F.SilkS")
			(hide yes)
			(effects
				(font
					(size 1.27 1.27)
				)
			)
		)
		(property "Value" ""
			(at 0 0 180)
			(layer "F.Fab")
			(effects
				(font
					(size 1.27 1.27)
				)
			)
		)
		(duplicate_pad_numbers_are_jumpers no)
		(fp_line
			(start 1.524 0.762)
			(end -1.524 0.762)
			(stroke
				(width 0.1524)
				(type default)
			)
			(layer "F.SilkS")
		)
		(fp_line
			(start 1.524 -0.762)
			(end 1.524 0.762)
			(stroke
				(width 0.1524)
				(type default)
			)
			(layer "F.SilkS")
		)
		(fp_line
			(start -1.524 0.762)
			(end -1.524 -0.762)
			(stroke
				(width 0.1524)
				(type default)
			)
			(layer "F.SilkS")
		)
		(fp_line
			(start -1.524 -0.762)
			(end 1.524 -0.762)
			(stroke
				(width 0.1524)
				(type default)
			)
			(layer "F.SilkS")
		)
		(fp_line
			(start 1.1049 0.724916)
			(end 1.1049 -0.724916)
			(stroke
				(width 0.1)
				(type default)
			)
			(layer "F.Fab")
		)
		(fp_line
			(start 1.1049 -0.724916)
			(end -1.1049 -0.724916)
			(stroke
				(width 0.1)
				(type default)
			)
			(layer "F.Fab")
		)
		(fp_line
			(start -1.1049 0.724916)
			(end 1.1049 0.724916)
			(stroke
				(width 0.1)
				(type default)
			)
			(layer "F.Fab")
		)
		(fp_line
			(start -1.1049 -0.724916)
			(end -1.1049 0.724916)
			(stroke
				(width 0.1)
				(type default)
			)
			(layer "F.Fab")
		)
		(pad "1" smd rect
			(at -0.889 0)
			(size 1.016 1.27)
			(layers "F.Cu" "F.Mask" "F.Paste")
			(net "GND")
		)
		(pad "2" smd rect
			(at 0.889 0)
			(size 1.016 1.27)
			(layers "F.Cu" "F.Mask" "F.Paste")
			(net "P12V_AUX")
		)
	)
	(footprint ""
		(layer "F.Cu")
		(at 44.178728 -343.952322 90)
		(property "Reference" "C2174"
			(at 0 0 90)
			(layer "F.SilkS")
			(hide yes)
			(effects
				(font
					(size 1.27 1.27)
				)
			)
		)
		(property "Value" ""
			(at 0 0 90)
			(layer "F.Fab")
			(effects
				(font
					(size 1.27 1.27)
				)
			)
		)
		(duplicate_pad_numbers_are_jumpers no)
		(fp_line
			(start 0.299974 -0.150114)
			(end 0.299974 0.150114)
			(stroke
				(width 0.1)
				(type default)
			)
			(layer "F.Fab")
		)
		(fp_line
			(start -0.299974 -0.150114)
			(end 0.299974 -0.150114)
			(stroke
				(width 0.1)
				(type default)
			)
			(layer "F.Fab")
		)
		(fp_line
			(start 0.299974 0.150114)
			(end -0.299974 0.150114)
			(stroke
				(width 0.1)
				(type default)
			)
			(layer "F.Fab")
		)
		(fp_line
			(start -0.299974 0.150114)
			(end -0.299974 -0.150114)
			(stroke
				(width 0.1)
				(type default)
			)
			(layer "F.Fab")
		)
		(pad "1" smd rect
			(at -0.2667 0 90)
			(size 0.3048 0.381)
			(layers "F.Cu" "F.Mask" "F.Paste")
			(net "P5E_PEX0_STN4_TX_DP<68>")
		)
		(pad "2" smd rect
			(at 0.2667 0 90)
			(size 0.3048 0.381)
			(layers "F.Cu" "F.Mask" "F.Paste")
			(net "P5E_PEX0_STN4_TX_C_DP<68>")
		)
	)
	(footprint ""
		(layer "F.Cu")
		(at 196.882512 -29.875734)
		(property "Reference" "PU126"
			(at -3.162046 -2.160524 90)
			(unlocked yes)
			(layer "F.SilkS")
			(effects
				(font
					(size 0.7874 0.5842)
					(thickness 0.1524)
				)
			)
		)
		(property "Value" ""
			(at 0 0 0)
			(layer "F.Fab")
			(effects
				(font
					(size 1.27 1.27)
				)
			)
		)
		(duplicate_pad_numbers_are_jumpers no)
		(fp_line
			(start -1.239774 -1.495298)
			(end 1.239774 -1.495298)
			(stroke
				(width 0.1524)
				(type default)
			)
			(layer "F.SilkS")
		)
		(fp_line
			(start -1.239774 1.495298)
			(end -1.239774 -1.495298)
			(stroke
				(width 0.1524)
				(type default)
			)
			(layer "F.SilkS")
		)
		(fp_line
			(start 1.239774 -1.495298)
			(end 1.239774 1.495298)
			(stroke
				(width 0.1524)
				(type default)
			)
			(layer "F.SilkS")
		)
		(fp_line
			(start 1.239774 1.495298)
			(end -1.239774 1.495298)
			(stroke
				(width 0.1524)
				(type default)
			)
			(layer "F.SilkS")
		)
		(fp_poly
			(pts
				(xy -2.797556 -1.220724) (xy -2.797556 -0.204724) (xy -1.781556 -0.712724)
			)
			(stroke
				(width 0)
				(type default)
			)
			(fill yes)
			(layer "F.SilkS")
		)
		(fp_line
			(start -0.8001 -1.050036)
			(end 0.8001 -1.050036)
			(stroke
				(width 0.1)
				(type default)
			)
			(layer "F.Fab")
		)
		(fp_line
			(start -0.8001 1.050036)
			(end -0.8001 -1.050036)
			(stroke
				(width 0.1)
				(type default)
			)
			(layer "F.Fab")
		)
		(fp_line
			(start 0.8001 -1.050036)
			(end 0.8001 1.050036)
			(stroke
				(width 0.1)
				(type default)
			)
			(layer "F.Fab")
		)
		(fp_line
			(start 0.8001 1.050036)
			(end -0.8001 1.050036)
			(stroke
				(width 0.1)
				(type default)
			)
			(layer "F.Fab")
		)
		(fp_poly
			(pts
				(xy -2.458974 -0.508) (xy -2.458974 0.508) (xy -1.442974 0)
			)
			(stroke
				(width 0)
				(type default)
			)
			(fill yes)
			(layer "F.Fab")
		)
		(pad "1_2" smd circle
			(at -0.374904 0 90)
			(size 0 0)
			(layers "F.Cu" "F.Mask" "F.Paste")
			(net "P3V3_AUX")
		)
		(pad "3" smd rect
			(at -0.499872 0.999998)
			(size 0.254 0.7112)
			(layers "F.Cu" "F.Mask" "F.Paste")
			(net "GND")
		)
		(pad "4" smd rect
			(at 0 0.999998)
			(size 0.254 0.7112)
			(layers "F.Cu" "F.Mask" "F.Paste")
			(net "P3V3_SSD7_CO_ILIMIT")
		)
		(pad "5" smd rect
			(at 0.499872 0.999998)
			(size 0.254 0.7112)
			(layers "F.Cu" "F.Mask" "F.Paste")
			(net "P3V3_SSD7_CO_MODE")
		)
		(pad "6_7" smd circle
			(at 0.374904 0 270)
			(size 0 0)
			(layers "F.Cu" "F.Mask" "F.Paste")
			(net "P3V3_SSD7")
		)
		(pad "8" smd rect
			(at 0.499872 -0.999998)
			(size 0.254 0.7112)
			(layers "F.Cu" "F.Mask" "F.Paste")
			(net "P3V3_SSD7_CO_GATE")
		)
		(pad "9" smd rect
			(at 0 -0.999998)
			(size 0.254 0.7112)
			(layers "F.Cu" "F.Mask" "F.Paste")
			(net "P3V3_SSD7_CO_EN")
		)
		(pad "10" smd rect
			(at -0.499872 -0.999998)
			(size 0.254 0.7112)
			(layers "F.Cu" "F.Mask" "F.Paste")
			(net "P3V3_SSD7_CO_DV_DT")
		)
	)
	(footprint ""
		(layer "F.Cu")
		(at 16.231362 -392.321034 180)
		(property "Reference" "R6756"
			(at 0 0 180)
			(layer "F.SilkS")
			(hide yes)
			(effects
				(font
					(size 1.27 1.27)
				)
			)
		)
		(property "Value" ""
			(at 0 0 180)
			(layer "F.Fab")
			(effects
				(font
					(size 1.27 1.27)
				)
			)
		)
		(duplicate_pad_numbers_are_jumpers no)
		(fp_line
			(start 0.7874 0.4064)
			(end -0.7874 0.4064)
			(stroke
				(width 0.1524)
				(type default)
			)
			(layer "F.SilkS")
		)
		(fp_line
			(start 0.7874 -0.4064)
			(end 0.7874 0.4064)
			(stroke
				(width 0.1524)
				(type default)
			)
			(layer "F.SilkS")
		)
		(fp_line
			(start -0.7874 0.4064)
			(end -0.7874 -0.4064)
			(stroke
				(width 0.1524)
				(type default)
			)
			(layer "F.SilkS")
		)
		(fp_line
			(start -0.7874 -0.4064)
			(end 0.7874 -0.4064)
			(stroke
				(width 0.1524)
				(type default)
			)
			(layer "F.SilkS")
		)
		(fp_line
			(start 0.67945 0.3048)
			(end 0.120396 0.3048)
			(stroke
				(width 0.1)
				(type default)
			)
			(layer "F.Fab")
		)
		(fp_line
			(start 0.67945 -0.3048)
			(end 0.67945 0.3048)
			(stroke
				(width 0.1)
				(type default)
			)
			(layer "F.Fab")
		)
		(fp_line
			(start 0.12065 -0.2794)
			(end 0.12065 -0.3048)
			(stroke
				(width 0.1)
				(type default)
			)
			(layer "F.Fab")
		)
		(fp_line
			(start 0.12065 -0.3048)
			(end 0.67945 -0.3048)
			(stroke
				(width 0.1)
				(type default)
			)
			(layer "F.Fab")
		)
		(fp_line
			(start 0.120396 0.3048)
			(end 0.120396 0.2794)
			(stroke
				(width 0.1)
				(type default)
			)
			(layer "F.Fab")
		)
		(fp_line
			(start 0.120396 0.2794)
			(end -0.12065 0.2794)
			(stroke
				(width 0.1)
				(type default)
			)
			(layer "F.Fab")
		)
		(fp_line
			(start -0.12065 0.3048)
			(end -0.67945 0.3048)
			(stroke
				(width 0.1)
				(type default)
			)
			(layer "F.Fab")
		)
		(fp_line
			(start -0.12065 0.2794)
			(end -0.12065 0.3048)
			(stroke
				(width 0.1)
				(type default)
			)
			(layer "F.Fab")
		)
		(fp_line
			(start -0.12065 -0.2794)
			(end 0.12065 -0.2794)
			(stroke
				(width 0.1)
				(type default)
			)
			(layer "F.Fab")
		)
		(fp_line
			(start -0.12065 -0.305054)
			(end -0.12065 -0.2794)
			(stroke
				(width 0.1)
				(type default)
			)
			(layer "F.Fab")
		)
		(fp_line
			(start -0.67945 0.3048)
			(end -0.67945 -0.305054)
			(stroke
				(width 0.1)
				(type default)
			)
			(layer "F.Fab")
		)
		(fp_line
			(start -0.67945 -0.305054)
			(end -0.12065 -0.305054)
			(stroke
				(width 0.1)
				(type default)
			)
			(layer "F.Fab")
		)
		(pad "1" smd circle
			(at -0.40005 0 180)
			(size 0 0)
			(layers "F.Cu" "F.Mask" "F.Paste")
			(net "P3V3_USB_8042")
		)
		(pad "2" smd circle
			(at 0.40005 0 180)
			(size 0 0)
			(layers "F.Cu" "F.Mask" "F.Paste")
			(net "BIC_USB_8042_HUB_PWRCTL3")
		)
	)
	(footprint ""
		(layer "F.Cu")
		(at 429.082454 -29.875734)
		(property "Reference" "PU134"
			(at -2.954528 -2.694178 90)
			(unlocked yes)
			(layer "F.SilkS")
			(effects
				(font
					(size 0.7874 0.5842)
					(thickness 0.1524)
				)
			)
		)
		(property "Value" ""
			(at 0 0 0)
			(layer "F.Fab")
			(effects
				(font
					(size 1.27 1.27)
				)
			)
		)
		(duplicate_pad_numbers_are_jumpers no)
		(fp_line
			(start -1.239774 -1.495298)
			(end 1.239774 -1.495298)
			(stroke
				(width 0.1524)
				(type default)
			)
			(layer "F.SilkS")
		)
		(fp_line
			(start -1.239774 1.495298)
			(end -1.239774 -1.495298)
			(stroke
				(width 0.1524)
				(type default)
			)
			(layer "F.SilkS")
		)
		(fp_line
			(start 1.239774 -1.495298)
			(end 1.239774 1.495298)
			(stroke
				(width 0.1524)
				(type default)
			)
			(layer "F.SilkS")
		)
		(fp_line
			(start 1.239774 1.495298)
			(end -1.239774 1.495298)
			(stroke
				(width 0.1524)
				(type default)
			)
			(layer "F.SilkS")
		)
		(fp_poly
			(pts
				(xy -2.07137 -1.295146) (xy -2.789682 -0.576834) (xy -1.712214 -0.217424)
			)
			(stroke
				(width 0)
				(type default)
			)
			(fill yes)
			(layer "F.SilkS")
		)
		(fp_line
			(start -0.8001 -1.050036)
			(end 0.8001 -1.050036)
			(stroke
				(width 0.1)
				(type default)
			)
			(layer "F.Fab")
		)
		(fp_line
			(start -0.8001 1.050036)
			(end -0.8001 -1.050036)
			(stroke
				(width 0.1)
				(type default)
			)
			(layer "F.Fab")
		)
		(fp_line
			(start 0.8001 -1.050036)
			(end 0.8001 1.050036)
			(stroke
				(width 0.1)
				(type default)
			)
			(layer "F.Fab")
		)
		(fp_line
			(start 0.8001 1.050036)
			(end -0.8001 1.050036)
			(stroke
				(width 0.1)
				(type default)
			)
			(layer "F.Fab")
		)
		(fp_poly
			(pts
				(xy -2.458974 -0.508) (xy -2.458974 0.508) (xy -1.442974 0)
			)
			(stroke
				(width 0)
				(type default)
			)
			(fill yes)
			(layer "F.Fab")
		)
		(pad "1_2" smd circle
			(at -0.374904 0 90)
			(size 0 0)
			(layers "F.Cu" "F.Mask" "F.Paste")
			(net "P3V3_AUX")
		)
		(pad "3" smd rect
			(at -0.499872 0.999998)
			(size 0.254 0.7112)
			(layers "F.Cu" "F.Mask" "F.Paste")
			(net "GND")
		)
		(pad "4" smd rect
			(at 0 0.999998)
			(size 0.254 0.7112)
			(layers "F.Cu" "F.Mask" "F.Paste")
			(net "P3V3_SSD15_CO_ILIMIT")
		)
		(pad "5" smd rect
			(at 0.499872 0.999998)
			(size 0.254 0.7112)
			(layers "F.Cu" "F.Mask" "F.Paste")
			(net "P3V3_SSD15_CO_MODE")
		)
		(pad "6_7" smd circle
			(at 0.374904 0 270)
			(size 0 0)
			(layers "F.Cu" "F.Mask" "F.Paste")
			(net "P3V3_SSD15")
		)
		(pad "8" smd rect
			(at 0.499872 -0.999998)
			(size 0.254 0.7112)
			(layers "F.Cu" "F.Mask" "F.Paste")
			(net "P3V3_SSD15_CO_GATE")
		)
		(pad "9" smd rect
			(at 0 -0.999998)
			(size 0.254 0.7112)
			(layers "F.Cu" "F.Mask" "F.Paste")
			(net "P3V3_SSD15_CO_EN")
		)
		(pad "10" smd rect
			(at -0.499872 -0.999998)
			(size 0.254 0.7112)
			(layers "F.Cu" "F.Mask" "F.Paste")
			(net "P3V3_SSD15_CO_DV_DT")
		)
	)
)
